# T6G (Grand Teton) — schematic netlist excerpt (pin names and nets, part order shuffled) for the footprints in the layout excerpt that follows; sources: Cadence DE-HDL packaged netlist, KiCad conversion of 04192023_DAF0TMB3IC0_F0TG_MB_C_brd_V02_OCP.brd

R171  Q_RES  33 5% CHIP  pkg 0402LF  page 80 : A = FM_I3C_CPU1_MUX1_OE_R_N ; B = FM_I3C_CPU1_MUX1_OE_N
C2520  Q_CAP  22UF 4V 20% X6S  pkg C0402  page 71 : A = PVDD18_S5_P0 ; B = GND

(kicad_pcb
	(version 20260206)
	(generator "pcbnew")
	(generator_version "10.0")
	(general
		(thickness 1.6)
		(legacy_teardrops no)
	)
	(paper "A4")
	(title_block
		(title "04192023_DAF0TMB3IC0_F0TG_MB_C_brd_V02_OCP.brd")
		(comment 1 "Grand Teton / footprints 6713-6714 of 8354")
	)
	(layers
		(0 "F.Cu" signal "TOP")
		(4 "In1.Cu" signal "GND")
		(6 "In2.Cu" signal "IN1")
		(8 "In3.Cu" signal "GND1")
		(10 "In4.Cu" signal "IN2")
		(12 "In5.Cu" signal "GND2")
		(14 "In6.Cu" signal "IN3")
		(16 "In7.Cu" signal "GND3")
		(18 "In8.Cu" signal "VCC")
		(20 "In9.Cu" signal "VCC1")
		(22 "In10.Cu" signal "GND4")
		(24 "In11.Cu" signal "IN4")
		(26 "In12.Cu" signal "GND5")
		(28 "In13.Cu" signal "IN5")
		(30 "In14.Cu" signal "GND6")
		(32 "In15.Cu" signal "IN6")
		(34 "In16.Cu" signal "GND7")
		(2 "B.Cu" signal "BOTTOM")
		(9 "F.Adhes" user "F.Adhesive")
		(11 "B.Adhes" user "B.Adhesive")
		(13 "F.Paste" user "Package Geometry/Pastemask Top")
		(15 "B.Paste" user "Package Geometry/Pastemask Bottom")
		(5 "F.SilkS" user "Ref Des/Silkscreen Top")
		(7 "B.SilkS" user "Ref Des/Silkscreen Bottom")
		(1 "F.Mask" user "Board Geometry/Soldermask Top")
		(3 "B.Mask" user "Board Geometry/Soldermask Bottom")
		(17 "Dwgs.User" user "User.Drawings")
		(19 "Cmts.User" user "User.Comments")
		(21 "Eco1.User" user "User.Eco1")
		(23 "Eco2.User" user "User.Eco2")
		(25 "Edge.Cuts" user "Board Geometry/Outline")
		(27 "Margin" user)
		(31 "F.CrtYd" user "Package Geometry/Place Bound Top")
		(29 "B.CrtYd" user "Package Geometry/Place Bound Bottom")
		(35 "F.Fab" user "Ref Des/Assembly Top")
		(33 "B.Fab" user "Ref Des/Assembly Bottom")
	)
	(footprint ""
		(layer "B.Cu")
		(at 171.2087 -111.183928)
		(property "Reference" "R171"
			(at 0 0 0)
			(layer "B.SilkS")
			(hide yes)
			(effects
				(font
					(size 1.27 1.27)
				)
				(justify mirror)
			)
		)
		(property "Value" ""
			(at 0 0 0)
			(layer "B.Fab")
			(effects
				(font
					(size 1.27 1.27)
				)
				(justify mirror)
			)
		)
		(duplicate_pad_numbers_are_jumpers no)
		(fp_line
			(start -0.7874 -0.4064)
			(end -0.7874 0.4064)
			(stroke
				(width 0.1524)
				(type default)
			)
			(layer "B.SilkS")
		)
		(fp_line
			(start -0.7874 0.4064)
			(end 0.7874 0.4064)
			(stroke
				(width 0.1524)
				(type default)
			)
			(layer "B.SilkS")
		)
		(fp_line
			(start 0.7874 -0.4064)
			(end -0.7874 -0.4064)
			(stroke
				(width 0.1524)
				(type default)
			)
			(layer "B.SilkS")
		)
		(fp_line
			(start 0.7874 0.4064)
			(end 0.7874 -0.4064)
			(stroke
				(width 0.1524)
				(type default)
			)
			(layer "B.SilkS")
		)
		(fp_line
			(start -0.67945 -0.3048)
			(end -0.67945 0.3048)
			(stroke
				(width 0.1)
				(type default)
			)
			(layer "B.Fab")
		)
		(fp_line
			(start -0.67945 0.3048)
			(end -0.120396 0.3048)
			(stroke
				(width 0.1)
				(type default)
			)
			(layer "B.Fab")
		)
		(fp_line
			(start -0.12065 -0.3048)
			(end -0.67945 -0.3048)
			(stroke
				(width 0.1)
				(type default)
			)
			(layer "B.Fab")
		)
		(fp_line
			(start -0.12065 -0.2794)
			(end -0.12065 -0.3048)
			(stroke
				(width 0.1)
				(type default)
			)
			(layer "B.Fab")
		)
		(fp_line
			(start -0.120396 0.2794)
			(end 0.12065 0.2794)
			(stroke
				(width 0.1)
				(type default)
			)
			(layer "B.Fab")
		)
		(fp_line
			(start -0.120396 0.3048)
			(end -0.120396 0.2794)
			(stroke
				(width 0.1)
				(type default)
			)
			(layer "B.Fab")
		)
		(fp_line
			(start 0.12065 -0.305054)
			(end 0.12065 -0.2794)
			(stroke
				(width 0.1)
				(type default)
			)
			(layer "B.Fab")
		)
		(fp_line
			(start 0.12065 -0.2794)
			(end -0.12065 -0.2794)
			(stroke
				(width 0.1)
				(type default)
			)
			(layer "B.Fab")
		)
		(fp_line
			(start 0.12065 0.2794)
			(end 0.12065 0.3048)
			(stroke
				(width 0.1)
				(type default)
			)
			(layer "B.Fab")
		)
		(fp_line
			(start 0.12065 0.3048)
			(end 0.67945 0.3048)
			(stroke
				(width 0.1)
				(type default)
			)
			(layer "B.Fab")
		)
		(fp_line
			(start 0.67945 -0.305054)
			(end 0.12065 -0.305054)
			(stroke
				(width 0.1)
				(type default)
			)
			(layer "B.Fab")
		)
		(fp_line
			(start 0.67945 0.3048)
			(end 0.67945 -0.305054)
			(stroke
				(width 0.1)
				(type default)
			)
			(layer "B.Fab")
		)
		(pad "1" smd circle
			(at 0.40005 0 180)
			(size 0 0)
			(layers "B.Cu" "B.Mask" "B.Paste")
			(net "FM_I3C_CPU1_MUX1_OE_R_N")
		)
		(pad "2" smd circle
			(at -0.40005 0 180)
			(size 0 0)
			(layers "B.Cu" "B.Mask" "B.Paste")
			(net "FM_I3C_CPU1_MUX1_OE_N")
		)
	)
	(footprint ""
		(layer "B.Cu")
		(at 346.545408 -254.95631)
		(property "Reference" "C2520"
			(at 0 0 0)
			(layer "B.SilkS")
			(hide yes)
			(effects
				(font
					(size 1.27 1.27)
				)
				(justify mirror)
			)
		)
		(property "Value" ""
			(at 0 0 0)
			(layer "B.Fab")
			(effects
				(font
					(size 1.27 1.27)
				)
				(justify mirror)
			)
		)
		(duplicate_pad_numbers_are_jumpers no)
		(fp_line
			(start -0.7874 -0.4064)
			(end -0.7874 0.4064)
			(stroke
				(width 0.1524)
				(type default)
			)
			(layer "B.SilkS")
		)
		(fp_line
			(start -0.7874 0.4064)
			(end 0.7874 0.4064)
			(stroke
				(width 0.1524)
				(type default)
			)
			(layer "B.SilkS")
		)
		(fp_line
			(start 0.7874 -0.4064)
			(end -0.7874 -0.4064)
			(stroke
				(width 0.1524)
				(type default)
			)
			(layer "B.SilkS")
		)
		(fp_line
			(start 0.7874 0.4064)
			(end 0.7874 -0.4064)
			(stroke
				(width 0.1524)
				(type default)
			)
			(layer "B.SilkS")
		)
		(fp_line
			(start -0.67945 -0.3048)
			(end -0.67945 0.3048)
			(stroke
				(width 0.1)
				(type default)
			)
			(layer "B.Fab")
		)
		(fp_line
			(start -0.67945 0.3048)
			(end -0.120396 0.3048)
			(stroke
				(width 0.1)
				(type default)
			)
			(layer "B.Fab")
		)
		(fp_line
			(start -0.12065 -0.3048)
			(end -0.67945 -0.3048)
			(stroke
				(width 0.1)
				(type default)
			)
			(layer "B.Fab")
		)
		(fp_line
			(start -0.12065 -0.2794)
			(end -0.12065 -0.3048)
			(stroke
				(width 0.1)
				(type default)
			)
			(layer "B.Fab")
		)
		(fp_line
			(start -0.120396 0.2794)
			(end 0.12065 0.2794)
			(stroke
				(width 0.1)
				(type default)
			)
			(layer "B.Fab")
		)
		(fp_line
			(start -0.120396 0.3048)
			(end -0.120396 0.2794)
			(stroke
				(width 0.1)
				(type default)
			)
			(layer "B.Fab")
		)
		(fp_line
			(start 0.12065 -0.305054)
			(end 0.12065 -0.2794)
			(stroke
				(width 0.1)
				(type default)
			)
			(layer "B.Fab")
		)
		(fp_line
			(start 0.12065 -0.2794)
			(end -0.12065 -0.2794)
			(stroke
				(width 0.1)
				(type default)
			)
			(layer "B.Fab")
		)
		(fp_line
			(start 0.12065 0.2794)
			(end 0.12065 0.3048)
			(stroke
				(width 0.1)
				(type default)
			)
			(layer "B.Fab")
		)
		(fp_line
			(start 0.12065 0.3048)
			(end 0.67945 0.3048)
			(stroke
				(width 0.1)
				(type default)
			)
			(layer "B.Fab")
		)
		(fp_line
			(start 0.67945 -0.305054)
			(end 0.12065 -0.305054)
			(stroke
				(width 0.1)
				(type default)
			)
			(layer "B.Fab")
		)
		(fp_line
			(start 0.67945 0.3048)
			(end 0.67945 -0.305054)
			(stroke
				(width 0.1)
				(type default)
			)
			(layer "B.Fab")
		)
		(pad "1" smd circle
			(at 0.40005 0 180)
			(size 0 0)
			(layers "B.Cu" "B.Mask" "B.Paste")
			(net "PVDD18_S5_P0")
		)
		(pad "2" smd circle
			(at -0.40005 0 180)
			(size 0 0)
			(layers "B.Cu" "B.Mask" "B.Paste")
			(net "GND")
		)
	)
)
